(kicad_pcb
	(version 20260206)
	(generator "pcbnew")
	(generator_version "10.0")
	(general
		(thickness 1.6)
		(legacy_teardrops no)
	)
	(paper "A4")
	(title_block
		(title "01162023_DA0F0TEBIF0_F0T_Expander_BD_F_brd_V02_OCP.brd")
		(comment 1 "Grand Teton / footprint 1840 of 9728 (U6), pads 332-440 of 484")
	)
	(layers
		(0 "F.Cu" signal "TOP")
		(4 "In1.Cu" signal "GND")
		(6 "In2.Cu" signal "VCC")
		(8 "In3.Cu" signal "VCC1")
		(10 "In4.Cu" signal "GND1")
		(12 "In5.Cu" signal "IN1")
		(14 "In6.Cu" signal "GND2")
		(16 "In7.Cu" signal "IN2")
		(18 "In8.Cu" signal "GND3")
		(20 "In9.Cu" signal "IN3")
		(22 "In10.Cu" signal "GND4")
		(24 "In11.Cu" signal "IN4")
		(26 "In12.Cu" signal "GND5")
		(28 "In13.Cu" signal "IN5")
		(30 "In14.Cu" signal "GND6")
		(32 "In15.Cu" signal "IN6")
		(34 "In16.Cu" signal "GND7")
		(2 "B.Cu" signal "BOTTOM")
		(9 "F.Adhes" user "F.Adhesive")
		(11 "B.Adhes" user "B.Adhesive")
		(13 "F.Paste" user "Package Geometry/Pastemask Top")
		(15 "B.Paste" user "Package Geometry/Pastemask Bottom")
		(5 "F.SilkS" user "Ref Des/Silkscreen Top")
		(7 "B.SilkS" user "Ref Des/Silkscreen Bottom")
		(1 "F.Mask" user "Board Geometry/Soldermask Top")
		(3 "B.Mask" user "Board Geometry/Soldermask Bottom")
		(17 "Dwgs.User" user "User.Drawings")
		(19 "Cmts.User" user "User.Comments")
		(21 "Eco1.User" user "User.Eco1")
		(23 "Eco2.User" user "User.Eco2")
		(25 "Edge.Cuts" user "Board Geometry/Outline")
		(27 "Margin" user)
		(31 "F.CrtYd" user "Package Geometry/Place Bound Top")
		(29 "B.CrtYd" user "Package Geometry/Place Bound Bottom")
		(35 "F.Fab" user "Ref Des/Assembly Top")
		(33 "B.Fab" user "Ref Des/Assembly Bottom")
	)
	(footprint ""
		(layer "F.Cu")
		(at 342.493854 -219.587064)
		(property "Reference" "U6"
			(at -10.3632 -10.963148 0)
			(unlocked yes)
			(layer "F.SilkS")
			(effects
				(font
					(size 0.7874 0.5842)
					(thickness 0.1524)
				)
				(justify left)
			)
		)
		(property "Value" ""
			(at 0 0 0)
			(layer "F.Fab")
			(effects
				(font
					(size 1.27 1.27)
				)
			)
		)
		(duplicate_pad_numbers_are_jumpers no)
		(pad "P2" smd circle
			(at -7.599934 1.999996)
			(size 0.4064 0.4064)
			(layers "F.Cu" "F.Mask" "F.Paste")
			(net "NIC7_MAIN_PWR_BIC_EN_R")
		)
		(pad "P3" smd circle
			(at -6.800088 1.999996)
			(size 0.4064 0.4064)
			(layers "F.Cu" "F.Mask" "F.Paste")
			(net "HSC_TIMER_R_N")
		)
		(pad "P4" smd circle
			(at -5.999988 1.999996)
			(size 0.4064 0.4064)
			(layers "F.Cu" "F.Mask" "F.Paste")
			(net "Net_1180")
		)
		(pad "P5" smd circle
			(at -5.199888 1.999996)
			(size 0.4064 0.4064)
			(layers "F.Cu" "F.Mask" "F.Paste")
			(net "SSD9_PWRDIS_BIC_R")
		)
		(pad "P6" smd circle
			(at -4.400042 1.999996)
			(size 0.4064 0.4064)
			(layers "F.Cu" "F.Mask" "F.Paste")
			(net "RST_PEX_SSD9_PERST_R_N")
		)
		(pad "P7" smd circle
			(at -3.599942 1.999996)
			(size 0.4064 0.4064)
			(layers "F.Cu" "F.Mask" "F.Paste")
			(net "SSD8_PWRDIS_BIC_R")
		)
		(pad "P8" smd circle
			(at -2.800096 1.999996)
			(size 0.4064 0.4064)
			(layers "F.Cu" "F.Mask" "F.Paste")
			(net "P3V3_FPGA_VCCIO3")
		)
		(pad "P9" smd circle
			(at -1.999996 1.999996)
			(size 0.4064 0.4064)
			(layers "F.Cu" "F.Mask" "F.Paste")
			(net "GND")
		)
		(pad "P10" smd circle
			(at -1.199896 1.999996)
			(size 0.4064 0.4064)
			(layers "F.Cu" "F.Mask" "F.Paste")
			(net "GND")
		)
		(pad "P11" smd circle
			(at -0.40005 1.999996)
			(size 0.4064 0.4064)
			(layers "F.Cu" "F.Mask" "F.Paste")
			(net "GND")
		)
		(pad "P12" smd circle
			(at 0.40005 1.999996)
			(size 0.4064 0.4064)
			(layers "F.Cu" "F.Mask" "F.Paste")
			(net "GND")
		)
		(pad "P13" smd circle
			(at 1.199896 1.999996)
			(size 0.4064 0.4064)
			(layers "F.Cu" "F.Mask" "F.Paste")
			(net "GND")
		)
		(pad "P14" smd circle
			(at 1.999996 1.999996)
			(size 0.4064 0.4064)
			(layers "F.Cu" "F.Mask" "F.Paste")
			(net "GND")
		)
		(pad "P15" smd circle
			(at 2.800096 1.999996)
			(size 0.4064 0.4064)
			(layers "F.Cu" "F.Mask" "F.Paste")
			(net "P3V3_FPGA_VCCIO1")
		)
		(pad "P16" smd circle
			(at 3.599942 1.999996)
			(size 0.4064 0.4064)
			(layers "F.Cu" "F.Mask" "F.Paste")
			(net "PRSNT_NIC1_FPGA_N")
		)
		(pad "P17" smd circle
			(at 4.400042 1.999996)
			(size 0.4064 0.4064)
			(layers "F.Cu" "F.Mask" "F.Paste")
			(net "PWRGD_P1V2_AUX_FPGA")
		)
		(pad "P18" smd circle
			(at 5.199888 1.999996)
			(size 0.4064 0.4064)
			(layers "F.Cu" "F.Mask" "F.Paste")
			(net "NIC0_MAIN_PWR_BIC_EN_R")
		)
		(pad "P19" smd circle
			(at 5.999988 1.999996)
			(size 0.4064 0.4064)
			(layers "F.Cu" "F.Mask" "F.Paste")
			(net "RST_PEX_NIC0_PERST_R_N")
		)
		(pad "P20" smd circle
			(at 6.800088 1.999996)
			(size 0.4064 0.4064)
			(layers "F.Cu" "F.Mask" "F.Paste")
			(net "NIC7_CLK_EN_N")
		)
		(pad "P21" smd circle
			(at 7.599934 1.999996)
			(size 0.4064 0.4064)
			(layers "F.Cu" "F.Mask" "F.Paste")
			(net "PWRGD_P12V_NIC7_R")
		)
		(pad "P22" smd circle
			(at 8.400034 1.999996)
			(size 0.4064 0.4064)
			(layers "F.Cu" "F.Mask" "F.Paste")
			(net "RST_NIC7_PERST_N")
		)
		(pad "R1" smd circle
			(at -8.400034 2.800096)
			(size 0.4064 0.4064)
			(layers "F.Cu" "F.Mask" "F.Paste")
			(net "Net_1192")
		)
		(pad "R2" smd circle
			(at -7.599934 2.800096)
			(size 0.4064 0.4064)
			(layers "F.Cu" "F.Mask" "F.Paste")
			(net "PRSNT_SSD10_FPGA_N")
		)
		(pad "R3" smd circle
			(at -6.800088 2.800096)
			(size 0.4064 0.4064)
			(layers "F.Cu" "F.Mask" "F.Paste")
			(net "SSD9_PEX_PWR_EN_R")
		)
		(pad "R4" smd circle
			(at -5.999988 2.800096)
			(size 0.4064 0.4064)
			(layers "F.Cu" "F.Mask" "F.Paste")
			(net "PRSNT_SSD9_FPGA_N")
		)
		(pad "R5" smd circle
			(at -5.199888 2.800096)
			(size 0.4064 0.4064)
			(layers "F.Cu" "F.Mask" "F.Paste")
			(net "MB_3V3IO_RSVD3_ISO_R")
		)
		(pad "R6" smd circle
			(at -4.400042 2.800096)
			(size 0.4064 0.4064)
			(layers "F.Cu" "F.Mask" "F.Paste")
			(net "PRSNT_SSD8_FPGA_N")
		)
		(pad "R7" smd circle
			(at -3.599942 2.800096)
			(size 0.4064 0.4064)
			(layers "F.Cu" "F.Mask" "F.Paste")
			(net "MB_3V3IO_RSVD1_ISO_R")
		)
		(pad "R8" smd circle
			(at -2.800096 2.800096)
			(size 0.4064 0.4064)
			(layers "F.Cu" "F.Mask" "F.Paste")
			(net "GND")
		)
		(pad "R9" smd circle
			(at -1.999996 2.800096)
			(size 0.4064 0.4064)
			(layers "F.Cu" "F.Mask" "F.Paste")
			(net "P3V3_FPGA_VCCIO2")
		)
		(pad "R10" smd circle
			(at -1.199896 2.800096)
			(size 0.4064 0.4064)
			(layers "F.Cu" "F.Mask" "F.Paste")
			(net "P3V3_FPGA_VCCIO2")
		)
		(pad "R11" smd circle
			(at -0.40005 2.800096)
			(size 0.4064 0.4064)
			(layers "F.Cu" "F.Mask" "F.Paste")
			(net "P3V3_FPGA_VCCIO2")
		)
		(pad "R12" smd circle
			(at 0.40005 2.800096)
			(size 0.4064 0.4064)
			(layers "F.Cu" "F.Mask" "F.Paste")
			(net "P3V3_FPGA_VCCIO2")
		)
		(pad "R13" smd circle
			(at 1.199896 2.800096)
			(size 0.4064 0.4064)
			(layers "F.Cu" "F.Mask" "F.Paste")
			(net "P3V3_FPGA_VCCIO2")
		)
		(pad "R14" smd circle
			(at 1.999996 2.800096)
			(size 0.4064 0.4064)
			(layers "F.Cu" "F.Mask" "F.Paste")
			(net "P3V3_FPGA_VCCIO2")
		)
		(pad "R15" smd circle
			(at 2.800096 2.800096)
			(size 0.4064 0.4064)
			(layers "F.Cu" "F.Mask" "F.Paste")
			(net "GND")
		)
		(pad "R16" smd circle
			(at 3.599942 2.800096)
			(size 0.4064 0.4064)
			(layers "F.Cu" "F.Mask" "F.Paste")
			(net "RST_MB_BIC_ISO_R_N")
		)
		(pad "R17" smd circle
			(at 4.400042 2.800096)
			(size 0.4064 0.4064)
			(layers "F.Cu" "F.Mask" "F.Paste")
			(net "NIC2_MAIN_PWR_BIC_EN_R")
		)
		(pad "R18" smd circle
			(at 5.199888 2.800096)
			(size 0.4064 0.4064)
			(layers "F.Cu" "F.Mask" "F.Paste")
			(net "RST_PEX_NIC2_PERST_R_N")
		)
		(pad "R19" smd circle
			(at 5.999988 2.800096)
			(size 0.4064 0.4064)
			(layers "F.Cu" "F.Mask" "F.Paste")
			(net "NIC2_PEX_PWR_EN_R")
		)
		(pad "R20" smd circle
			(at 6.800088 2.800096)
			(size 0.4064 0.4064)
			(layers "F.Cu" "F.Mask" "F.Paste")
			(net "PRSNT_NIC2_FPGA_N")
		)
		(pad "R21" smd circle
			(at 7.599934 2.800096)
			(size 0.4064 0.4064)
			(layers "F.Cu" "F.Mask" "F.Paste")
			(net "NIC7_MAIN_PWR_EN")
		)
		(pad "R22" smd circle
			(at 8.400034 2.800096)
			(size 0.4064 0.4064)
			(layers "F.Cu" "F.Mask" "F.Paste")
			(net "PWRGD_NIC7_PWR_GOOD_R")
		)
		(pad "T1" smd circle
			(at -8.400034 3.599942)
			(size 0.4064 0.4064)
			(layers "F.Cu" "F.Mask" "F.Paste")
			(net "MB_3V3IO_RSVD4_ISO_R")
		)
		(pad "T2" smd circle
			(at -7.599934 3.599942)
			(size 0.4064 0.4064)
			(layers "F.Cu" "F.Mask" "F.Paste")
			(net "RST_PEX_SSD8_PERST_R_N")
		)
		(pad "T3" smd circle
			(at -6.800088 3.599942)
			(size 0.4064 0.4064)
			(layers "F.Cu" "F.Mask" "F.Paste")
			(net "SSD7_PWRDIS_BIC_R")
		)
		(pad "T4" smd circle
			(at -5.999988 3.599942)
			(size 0.4064 0.4064)
			(layers "F.Cu" "F.Mask" "F.Paste")
			(net "RST_PEX_SSD7_PERST_R_N")
		)
		(pad "T5" smd circle
			(at -5.199888 3.599942)
			(size 0.4064 0.4064)
			(layers "F.Cu" "F.Mask" "F.Paste")
			(net "SSD7_PEX_PWR_EN_R")
		)
		(pad "T6" smd circle
			(at -4.400042 3.599942)
			(size 0.4064 0.4064)
			(layers "F.Cu" "F.Mask" "F.Paste")
			(net "PRSNT_SSD7_FPGA_N")
		)
		(pad "T7" smd circle
			(at -3.599942 3.599942)
			(size 0.4064 0.4064)
			(layers "F.Cu" "F.Mask" "F.Paste")
			(net "PRSNT_SSD11_FPGA_N")
		)
		(pad "T8" smd circle
			(at -2.800096 3.599942)
			(size 0.4064 0.4064)
			(layers "F.Cu" "F.Mask" "F.Paste")
			(net "SSD9_PWRDIS")
		)
		(pad "T9" smd circle
			(at -1.999996 3.599942)
			(size 0.4064 0.4064)
			(layers "F.Cu" "F.Mask" "F.Paste")
			(net "SSD11_PWR_EN")
		)
		(pad "T10" smd circle
			(at -1.199896 3.599942)
			(size 0.4064 0.4064)
			(layers "F.Cu" "F.Mask" "F.Paste")
			(net "SSD12_CLK_EN_N")
		)
		(pad "T11" smd circle
			(at -0.40005 3.599942)
			(size 0.4064 0.4064)
			(layers "F.Cu" "F.Mask" "F.Paste")
			(net "PRSNT_SSD14_R_N")
		)
		(pad "T12" smd circle
			(at 0.40005 3.599942)
			(size 0.4064 0.4064)
			(layers "F.Cu" "F.Mask" "F.Paste")
			(net "FM_PFR_LED_AMBER")
		)
		(pad "T13" smd circle
			(at 1.199896 3.599942)
			(size 0.4064 0.4064)
			(layers "F.Cu" "F.Mask" "F.Paste")
			(net "SSD0_PEX_PWR_EN_R")
		)
		(pad "T14" smd circle
			(at 1.999996 3.599942)
			(size 0.4064 0.4064)
			(layers "F.Cu" "F.Mask" "F.Paste")
			(net "RST_PEX_SSD0_PERST_R_N")
		)
		(pad "T15" smd circle
			(at 2.800096 3.599942)
			(size 0.4064 0.4064)
			(layers "F.Cu" "F.Mask" "F.Paste")
			(net "RST_PEX_SSD5_PERST_R_N")
		)
		(pad "T16" smd circle
			(at 3.599942 3.599942)
			(size 0.4064 0.4064)
			(layers "F.Cu" "F.Mask" "F.Paste")
			(net "FPGA_PEX3_MODE_SEL1")
		)
		(pad "T17" smd circle
			(at 4.400042 3.599942)
			(size 0.4064 0.4064)
			(layers "F.Cu" "F.Mask" "F.Paste")
			(net "NIC3_MAIN_PWR_BIC_EN_R")
		)
		(pad "T18" smd circle
			(at 5.199888 3.599942)
			(size 0.4064 0.4064)
			(layers "F.Cu" "F.Mask" "F.Paste")
			(net "RST_PEX_NIC3_PERST_R_N")
		)
		(pad "T19" smd circle
			(at 5.999988 3.599942)
			(size 0.4064 0.4064)
			(layers "F.Cu" "F.Mask" "F.Paste")
			(net "NIC3_PEX_PWR_EN_R")
		)
		(pad "T20" smd circle
			(at 6.800088 3.599942)
			(size 0.4064 0.4064)
			(layers "F.Cu" "F.Mask" "F.Paste")
			(net "PRSNT_NIC3_FPGA_N")
		)
		(pad "T21" smd circle
			(at 7.599934 3.599942)
			(size 0.4064 0.4064)
			(layers "F.Cu" "F.Mask" "F.Paste")
			(net "NIC0_PEX_PWR_EN_R")
		)
		(pad "T22" smd circle
			(at 8.400034 3.599942)
			(size 0.4064 0.4064)
			(layers "F.Cu" "F.Mask" "F.Paste")
			(net "PRSNT_NIC0_FPGA_N")
		)
		(pad "U1" smd circle
			(at -8.400034 4.400042)
			(size 0.4064 0.4064)
			(layers "F.Cu" "F.Mask" "F.Paste")
			(net "SSD8_PEX_PWR_EN_R")
		)
		(pad "U2" smd circle
			(at -7.599934 4.400042)
			(size 0.4064 0.4064)
			(layers "F.Cu" "F.Mask" "F.Paste")
			(net "CLK_25M_FPGA_R")
		)
		(pad "U3" smd circle
			(at -6.800088 4.400042)
			(size 0.4064 0.4064)
			(layers "F.Cu" "F.Mask" "F.Paste")
			(net "SSD13_PWRDIS_BIC_R")
		)
		(pad "U4" smd circle
			(at -5.999988 4.400042)
			(size 0.4064 0.4064)
			(layers "F.Cu" "F.Mask" "F.Paste")
			(net "RST_PEX_SSD13_PERST_R_N")
		)
		(pad "U5" smd circle
			(at -5.199888 4.400042)
			(size 0.4064 0.4064)
			(layers "F.Cu" "F.Mask" "F.Paste")
			(net "SSD12_PWRDIS_BIC_R")
		)
		(pad "U6" smd circle
			(at -4.400042 4.400042)
			(size 0.4064 0.4064)
			(layers "F.Cu" "F.Mask" "F.Paste")
			(net "SSD8_PWR_EN")
		)
		(pad "U7" smd circle
			(at -3.599942 4.400042)
			(size 0.4064 0.4064)
			(layers "F.Cu" "F.Mask" "F.Paste")
			(net "SSD9_PWR_EN")
		)
		(pad "U8" smd circle
			(at -2.800096 4.400042)
			(size 0.4064 0.4064)
			(layers "F.Cu" "F.Mask" "F.Paste")
			(net "PWRGD_P3V3_SSD11_R")
		)
		(pad "U9" smd circle
			(at -1.999996 4.400042)
			(size 0.4064 0.4064)
			(layers "F.Cu" "F.Mask" "F.Paste")
			(net "SSD11_PWRDIS")
		)
		(pad "U10" smd circle
			(at -1.199896 4.400042)
			(size 0.4064 0.4064)
			(layers "F.Cu" "F.Mask" "F.Paste")
			(net "PRSNT_SSD13_R_N")
		)
		(pad "U11" smd circle
			(at -0.40005 4.400042)
			(size 0.4064 0.4064)
			(layers "F.Cu" "F.Mask" "F.Paste")
			(net "PWRGD_P12V_SSD14_R")
		)
		(pad "U12" smd circle
			(at 0.40005 4.400042)
			(size 0.4064 0.4064)
			(layers "F.Cu" "F.Mask" "F.Paste")
			(net "FM_PFR_LED_BLUE")
		)
		(pad "U13" smd circle
			(at 1.199896 4.400042)
			(size 0.4064 0.4064)
			(layers "F.Cu" "F.Mask" "F.Paste")
			(net "SSD15_PWR_EN")
		)
		(pad "U14" smd circle
			(at 1.999996 4.400042)
			(size 0.4064 0.4064)
			(layers "F.Cu" "F.Mask" "F.Paste")
			(net "SSD0_PWRDIS_BIC_R")
		)
		(pad "U15" smd circle
			(at 2.800096 4.400042)
			(size 0.4064 0.4064)
			(layers "F.Cu" "F.Mask" "F.Paste")
			(net "SSD3_PEX_PWR_EN_R")
		)
		(pad "U16" smd circle
			(at 3.599942 4.400042)
			(size 0.4064 0.4064)
			(layers "F.Cu" "F.Mask" "F.Paste")
			(net "SSD5_PWRDIS_BIC_R")
		)
		(pad "U17" smd circle
			(at 4.400042 4.400042)
			(size 0.4064 0.4064)
			(layers "F.Cu" "F.Mask" "F.Paste")
			(net "NIC5_PEX_PWR_EN_R")
		)
		(pad "U18" smd circle
			(at 5.199888 4.400042)
			(size 0.4064 0.4064)
			(layers "F.Cu" "F.Mask" "F.Paste")
			(net "NIC4_MAIN_PWR_BIC_EN_R")
		)
		(pad "U19" smd circle
			(at 5.999988 4.400042)
			(size 0.4064 0.4064)
			(layers "F.Cu" "F.Mask" "F.Paste")
			(net "RST_PEX_NIC4_PERST_R_N")
		)
		(pad "U20" smd circle
			(at 6.800088 4.400042)
			(size 0.4064 0.4064)
			(layers "F.Cu" "F.Mask" "F.Paste")
			(net "PWRGD_PEX1_P1V8_PLL_R")
		)
		(pad "U21" smd circle
			(at 7.599934 4.400042)
			(size 0.4064 0.4064)
			(layers "F.Cu" "F.Mask" "F.Paste")
			(net "RST_PEX_NIC1_PERST_R_N")
		)
		(pad "U22" smd circle
			(at 8.400034 4.400042)
			(size 0.4064 0.4064)
			(layers "F.Cu" "F.Mask" "F.Paste")
			(net "NIC1_PEX_PWR_EN_R")
		)
		(pad "V1" smd circle
			(at -8.400034 5.199888)
			(size 0.4064 0.4064)
			(layers "F.Cu" "F.Mask" "F.Paste")
			(net "GPU_3V3IO_RSVD4_ISO_R")
		)
		(pad "V2" smd circle
			(at -7.599934 5.199888)
			(size 0.4064 0.4064)
			(layers "F.Cu" "F.Mask" "F.Paste")
			(net "GND")
		)
		(pad "V3" smd circle
			(at -6.800088 5.199888)
			(size 0.4064 0.4064)
			(layers "F.Cu" "F.Mask" "F.Paste")
			(net "P3V3_FPGA_VCCIO3")
		)
		(pad "V4" smd circle
			(at -5.999988 5.199888)
			(size 0.4064 0.4064)
			(layers "F.Cu" "F.Mask" "F.Paste")
			(net "GPU_3V3IO_RSVD3_ISO_R")
		)
		(pad "V5" smd circle
			(at -5.199888 5.199888)
			(size 0.4064 0.4064)
			(layers "F.Cu" "F.Mask" "F.Paste")
			(net "SSD11_PEX_PWR_EN_R")
		)
		(pad "V6" smd circle
			(at -4.400042 5.199888)
			(size 0.4064 0.4064)
			(layers "F.Cu" "F.Mask" "F.Paste")
			(net "PWRGD_P3V3_SSD8_R")
		)
		(pad "V7" smd circle
			(at -3.599942 5.199888)
			(size 0.4064 0.4064)
			(layers "F.Cu" "F.Mask" "F.Paste")
			(net "RST_SSD10_PERST_N")
		)
		(pad "V8" smd circle
			(at -2.800096 5.199888)
			(size 0.4064 0.4064)
			(layers "F.Cu" "F.Mask" "F.Paste")
			(net "PWRGD_P12V_SSD11_R")
		)
		(pad "V9" smd circle
			(at -1.999996 5.199888)
			(size 0.4064 0.4064)
			(layers "F.Cu" "F.Mask" "F.Paste")
			(net "RST_SSD11_PERST_N")
		)
		(pad "V10" smd circle
			(at -1.199896 5.199888)
			(size 0.4064 0.4064)
			(layers "F.Cu" "F.Mask" "F.Paste")
			(net "PWRGD_P12V_SSD13_R")
		)
		(pad "V11" smd circle
			(at -0.40005 5.199888)
			(size 0.4064 0.4064)
			(layers "F.Cu" "F.Mask" "F.Paste")
			(net "SSD14_PWRDIS")
		)
		(pad "V12" smd circle
			(at 0.40005 5.199888)
			(size 0.4064 0.4064)
			(layers "F.Cu" "F.Mask" "F.Paste")
			(net "RST_SMB_FPGA_R_N")
		)
		(pad "V13" smd circle
			(at 1.199896 5.199888)
			(size 0.4064 0.4064)
			(layers "F.Cu" "F.Mask" "F.Paste")
			(net "PWRGD_P3V3_SSD15_R")
		)
		(pad "V14" smd circle
			(at 1.999996 5.199888)
			(size 0.4064 0.4064)
			(layers "F.Cu" "F.Mask" "F.Paste")
			(net "FPGA_PEX0_MODE_SEL2")
		)
		(pad "V15" smd circle
			(at 2.800096 5.199888)
			(size 0.4064 0.4064)
			(layers "F.Cu" "F.Mask" "F.Paste")
			(net "PRSNT_SSD3_FPGA_N")
		)
		(pad "V16" smd circle
			(at 3.599942 5.199888)
			(size 0.4064 0.4064)
			(layers "F.Cu" "F.Mask" "F.Paste")
			(net "PRSNT_SSD4_FPGA_N")
		)
		(pad "V17" smd circle
			(at 4.400042 5.199888)
			(size 0.4064 0.4064)
			(layers "F.Cu" "F.Mask" "F.Paste")
			(net "SSD6_PWRDIS_BIC_R")
		)
		(pad "V18" smd circle
			(at 5.199888 5.199888)
			(size 0.4064 0.4064)
			(layers "F.Cu" "F.Mask" "F.Paste")
			(net "NIC5_MAIN_PWR_BIC_EN_R")
		)
		(pad "V19" smd circle
			(at 5.999988 5.199888)
			(size 0.4064 0.4064)
			(layers "F.Cu" "F.Mask" "F.Paste")
			(net "RST_PEX_NIC5_PERST_R_N")
		)
		(pad "V20" smd circle
			(at 6.800088 5.199888)
			(size 0.4064 0.4064)
			(layers "F.Cu" "F.Mask" "F.Paste")
			(net "P3V3_FPGA_VCCIO1")
		)
		(pad "V21" smd circle
			(at 7.599934 5.199888)
			(size 0.4064 0.4064)
			(layers "F.Cu" "F.Mask" "F.Paste")
			(net "GND")
		)
		(pad "V22" smd circle
			(at 8.400034 5.199888)
			(size 0.4064 0.4064)
			(layers "F.Cu" "F.Mask" "F.Paste")
			(net "NIC1_MAIN_PWR_BIC_EN_R")
		)
	)
)
